# S9S_MB_2U (Grand Teton) — schematic netlist excerpt (pin names and nets, part order shuffled) for the footprints in the layout excerpt that follows; sources: Cadence DE-HDL packaged netlist, KiCad conversion of 03242023_DA0F0TMBIJ0_F0T_Motherboard_J_brd_V01_OCP.brd

R3713  Q_RES  0 5% CHIP  pkg 0402LF  page 233 : A = SMB_VR_3V3AUX_SCL_R6 ; B = SMB_VR_3V3AUX_SCL
R1479  Q_RES  10 1% CHIP  pkg 0402LF  page 202 : A = ESPI_LFRAME_N_BMC_CS0_N ; B = ESPI_HOST_LPC_BMC_LFRAME_N

(kicad_pcb
	(version 20260206)
	(generator "pcbnew")
	(generator_version "10.0")
	(general
		(thickness 1.6)
		(legacy_teardrops no)
	)
	(paper "A4")
	(title_block
		(title "03242023_DA0F0TMBIJ0_F0T_Motherboard_J_brd_V01_OCP.brd")
		(comment 1 "Grand Teton / footprints 784-785 of 6105")
	)
	(layers
		(0 "F.Cu" signal "TOP")
		(4 "In1.Cu" signal "GND")
		(6 "In2.Cu" signal "IN1")
		(8 "In3.Cu" signal "GND1")
		(10 "In4.Cu" signal "IN2")
		(12 "In5.Cu" signal "GND2")
		(14 "In6.Cu" signal "IN3")
		(16 "In7.Cu" signal "GND3")
		(18 "In8.Cu" signal "VCC")
		(20 "In9.Cu" signal "VCC1")
		(22 "In10.Cu" signal "GND4")
		(24 "In11.Cu" signal "IN4")
		(26 "In12.Cu" signal "GND5")
		(28 "In13.Cu" signal "IN5")
		(30 "In14.Cu" signal "GND6")
		(32 "In15.Cu" signal "IN6")
		(34 "In16.Cu" signal "GND7")
		(2 "B.Cu" signal "BOTTOM")
		(9 "F.Adhes" user "F.Adhesive")
		(11 "B.Adhes" user "B.Adhesive")
		(13 "F.Paste" user "Package Geometry/Pastemask Top")
		(15 "B.Paste" user "Package Geometry/Pastemask Bottom")
		(5 "F.SilkS" user "Ref Des/Silkscreen Top")
		(7 "B.SilkS" user "Ref Des/Silkscreen Bottom")
		(1 "F.Mask" user "Board Geometry/Soldermask Top")
		(3 "B.Mask" user "Board Geometry/Soldermask Bottom")
		(17 "Dwgs.User" user "User.Drawings")
		(19 "Cmts.User" user "User.Comments")
		(21 "Eco1.User" user "User.Eco1")
		(23 "Eco2.User" user "User.Eco2")
		(25 "Edge.Cuts" user "Board Geometry/Outline")
		(27 "Margin" user)
		(31 "F.CrtYd" user "Package Geometry/Place Bound Top")
		(29 "B.CrtYd" user "Package Geometry/Place Bound Bottom")
		(35 "F.Fab" user "Ref Des/Assembly Top")
		(33 "B.Fab" user "Ref Des/Assembly Bottom")
	)
	(footprint ""
		(layer "F.Cu")
		(at 336.018124 -25.070562 -90)
		(property "Reference" "R1479"
			(at 0 0 270)
			(layer "F.SilkS")
			(hide yes)
			(effects
				(font
					(size 1.27 1.27)
				)
			)
		)
		(property "Value" ""
			(at 0 0 270)
			(layer "F.Fab")
			(effects
				(font
					(size 1.27 1.27)
				)
			)
		)
		(duplicate_pad_numbers_are_jumpers no)
		(fp_line
			(start -0.7874 0.4064)
			(end -0.7874 -0.4064)
			(stroke
				(width 0.1524)
				(type default)
			)
			(layer "F.SilkS")
		)
		(fp_line
			(start 0.7874 0.4064)
			(end -0.7874 0.4064)
			(stroke
				(width 0.1524)
				(type default)
			)
			(layer "F.SilkS")
		)
		(fp_line
			(start -0.7874 -0.4064)
			(end 0.7874 -0.4064)
			(stroke
				(width 0.1524)
				(type default)
			)
			(layer "F.SilkS")
		)
		(fp_line
			(start 0.7874 -0.4064)
			(end 0.7874 0.4064)
			(stroke
				(width 0.1524)
				(type default)
			)
			(layer "F.SilkS")
		)
		(fp_line
			(start -0.67945 0.3048)
			(end -0.67945 -0.305054)
			(stroke
				(width 0.1)
				(type default)
			)
			(layer "F.Fab")
		)
		(fp_line
			(start -0.12065 0.3048)
			(end -0.67945 0.3048)
			(stroke
				(width 0.1)
				(type default)
			)
			(layer "F.Fab")
		)
		(fp_line
			(start 0.120396 0.3048)
			(end 0.120396 0.2794)
			(stroke
				(width 0.1)
				(type default)
			)
			(layer "F.Fab")
		)
		(fp_line
			(start 0.67945 0.3048)
			(end 0.120396 0.3048)
			(stroke
				(width 0.1)
				(type default)
			)
			(layer "F.Fab")
		)
		(fp_line
			(start -0.12065 0.2794)
			(end -0.12065 0.3048)
			(stroke
				(width 0.1)
				(type default)
			)
			(layer "F.Fab")
		)
		(fp_line
			(start 0.120396 0.2794)
			(end -0.12065 0.2794)
			(stroke
				(width 0.1)
				(type default)
			)
			(layer "F.Fab")
		)
		(fp_line
			(start -0.12065 -0.2794)
			(end 0.12065 -0.2794)
			(stroke
				(width 0.1)
				(type default)
			)
			(layer "F.Fab")
		)
		(fp_line
			(start 0.12065 -0.2794)
			(end 0.12065 -0.3048)
			(stroke
				(width 0.1)
				(type default)
			)
			(layer "F.Fab")
		)
		(fp_line
			(start 0.12065 -0.3048)
			(end 0.67945 -0.3048)
			(stroke
				(width 0.1)
				(type default)
			)
			(layer "F.Fab")
		)
		(fp_line
			(start 0.67945 -0.3048)
			(end 0.67945 0.3048)
			(stroke
				(width 0.1)
				(type default)
			)
			(layer "F.Fab")
		)
		(fp_line
			(start -0.67945 -0.305054)
			(end -0.12065 -0.305054)
			(stroke
				(width 0.1)
				(type default)
			)
			(layer "F.Fab")
		)
		(fp_line
			(start -0.12065 -0.305054)
			(end -0.12065 -0.2794)
			(stroke
				(width 0.1)
				(type default)
			)
			(layer "F.Fab")
		)
		(pad "1" smd circle
			(at -0.40005 0 270)
			(size 0 0)
			(layers "F.Cu" "F.Mask" "F.Paste")
			(net "ESPI_LFRAME_N_BMC_CS0_N")
		)
		(pad "2" smd circle
			(at 0.40005 0 270)
			(size 0 0)
			(layers "F.Cu" "F.Mask" "F.Paste")
			(net "ESPI_HOST_LPC_BMC_LFRAME_N")
		)
	)
	(footprint ""
		(layer "F.Cu")
		(at 54.242716 -112.96269 180)
		(property "Reference" "R3713"
			(at 0 0 180)
			(layer "F.SilkS")
			(hide yes)
			(effects
				(font
					(size 1.27 1.27)
				)
			)
		)
		(property "Value" ""
			(at 0 0 180)
			(layer "F.Fab")
			(effects
				(font
					(size 1.27 1.27)
				)
			)
		)
		(duplicate_pad_numbers_are_jumpers no)
		(fp_line
			(start 0.7874 0.4064)
			(end -0.7874 0.4064)
			(stroke
				(width 0.1524)
				(type default)
			)
			(layer "F.SilkS")
		)
		(fp_line
			(start 0.7874 -0.4064)
			(end 0.7874 0.4064)
			(stroke
				(width 0.1524)
				(type default)
			)
			(layer "F.SilkS")
		)
		(fp_line
			(start -0.7874 0.4064)
			(end -0.7874 -0.4064)
			(stroke
				(width 0.1524)
				(type default)
			)
			(layer "F.SilkS")
		)
		(fp_line
			(start -0.7874 -0.4064)
			(end 0.7874 -0.4064)
			(stroke
				(width 0.1524)
				(type default)
			)
			(layer "F.SilkS")
		)
		(fp_line
			(start 0.67945 0.3048)
			(end 0.120396 0.3048)
			(stroke
				(width 0.1)
				(type default)
			)
			(layer "F.Fab")
		)
		(fp_line
			(start 0.67945 -0.3048)
			(end 0.67945 0.3048)
			(stroke
				(width 0.1)
				(type default)
			)
			(layer "F.Fab")
		)
		(fp_line
			(start 0.12065 -0.2794)
			(end 0.12065 -0.3048)
			(stroke
				(width 0.1)
				(type default)
			)
			(layer "F.Fab")
		)
		(fp_line
			(start 0.12065 -0.3048)
			(end 0.67945 -0.3048)
			(stroke
				(width 0.1)
				(type default)
			)
			(layer "F.Fab")
		)
		(fp_line
			(start 0.120396 0.3048)
			(end 0.120396 0.2794)
			(stroke
				(width 0.1)
				(type default)
			)
			(layer "F.Fab")
		)
		(fp_line
			(start 0.120396 0.2794)
			(end -0.12065 0.2794)
			(stroke
				(width 0.1)
				(type default)
			)
			(layer "F.Fab")
		)
		(fp_line
			(start -0.12065 0.3048)
			(end -0.67945 0.3048)
			(stroke
				(width 0.1)
				(type default)
			)
			(layer "F.Fab")
		)
		(fp_line
			(start -0.12065 0.2794)
			(end -0.12065 0.3048)
			(stroke
				(width 0.1)
				(type default)
			)
			(layer "F.Fab")
		)
		(fp_line
			(start -0.12065 -0.2794)
			(end 0.12065 -0.2794)
			(stroke
				(width 0.1)
				(type default)
			)
			(layer "F.Fab")
		)
		(fp_line
			(start -0.12065 -0.305054)
			(end -0.12065 -0.2794)
			(stroke
				(width 0.1)
				(type default)
			)
			(layer "F.Fab")
		)
		(fp_line
			(start -0.67945 0.3048)
			(end -0.67945 -0.305054)
			(stroke
				(width 0.1)
				(type default)
			)
			(layer "F.Fab")
		)
		(fp_line
			(start -0.67945 -0.305054)
			(end -0.12065 -0.305054)
			(stroke
				(width 0.1)
				(type default)
			)
			(layer "F.Fab")
		)
		(pad "1" smd circle
			(at -0.40005 0 180)
			(size 0 0)
			(layers "F.Cu" "F.Mask" "F.Paste")
			(net "SMB_VR_3V3AUX_SCL_R6")
		)
		(pad "2" smd circle
			(at 0.40005 0 180)
			(size 0 0)
			(layers "F.Cu" "F.Mask" "F.Paste")
			(net "SMB_VR_3V3AUX_SCL")
		)
	)
)
